FILE_TYPE = MACRO_DRAWING;
SET COLOR_WIRE YELLOW;
SET COLOR_PROP MONO;
SET COLOR_DOT WHITE;
SET COLOR_ARC YELLOW;
SET COLOR_BODY GREEN;
SET COLOR_NOTE MONO;
SET PROP_DISPLAY VALUE;
SET PAGE_NUMBER P140;
FORCEADD M25PE16..1
(-2350 2700);
FORCEPROP 2 LASTPIN (-2700 2500) $PN 3
J 2
(-2710 2510);
DISPLAY 0.617021 (-2710 2510);
PAINT ORANGE (-2710 2510);
FORCEPROP 2 LASTPIN (-2700 2550) $PN 1
J 2
(-2710 2560);
DISPLAY 0.617021 (-2710 2560);
PAINT ORANGE (-2710 2560);
FORCEPROP 2 LASTPIN (-2700 2650) $PN 6
J 2
(-2710 2660);
DISPLAY 0.617021 (-2710 2660);
PAINT ORANGE (-2710 2660);
FORCEPROP 2 LASTPIN (-2700 2750) $PN 5
J 2
(-2710 2760);
DISPLAY 0.617021 (-2710 2760);
PAINT ORANGE (-2710 2760);
FORCEPROP 2 LASTPIN (-2700 2600) $PN 7
J 2
(-2710 2610);
DISPLAY 0.617021 (-2710 2610);
PAINT ORANGE (-2710 2610);
FORCEPROP 2 LASTPIN (-2700 2850) $PN 8
J 2
(-2710 2860);
DISPLAY 0.617021 (-2710 2860);
PAINT ORANGE (-2710 2860);
FORCEPROP 1 LAST PART_NUMBER H77797-001
J 0
(-2650 2350);
DISPLAY 0.617021 (-2650 2350);
PAINT BLUE (-2650 2350);
FORCEPROP 1 LAST MATERIAL IC
J 0
(-2650 3050);
DISPLAY 0.617021 (-2650 3050);
PAINT SKYBLUE (-2650 3050);
FORCEPROP 1 LAST LOCATION U9E1
J 1
(-2175 3075);
DISPLAY 0.617021 (-2175 3075);
PAINT AQUA (-2175 3075);
FORCEPROP 2 LASTPIN (-2000 2500) $PN 4
J 0
(-1990 2510);
DISPLAY 0.617021 (-1990 2510);
PAINT ORANGE (-1990 2510);
FORCEPROP 2 LASTPIN (-2000 2750) $PN 2
J 0
(-1990 2760);
DISPLAY 0.617021 (-1990 2760);
PAINT ORANGE (-1990 2760);
FORCEPROP 2 LAST CDS_LIB mstr_memory
J 0
(-2350 2700);
PAINT ORANGE (-2350 2700);
DISPLAY INVISIBLE (-2350 2700);
FORCEPROP 1 LAST PATH I1
J 0
(-2300 3050);
PAINT GREEN (-2300 3050);
DISPLAY INVISIBLE (-2300 3050);
FORCEPROP 1 LAST PACK_TYPE SM
J 0
(-2650 3150);
PAINT SKYBLUE (-2650 3150);
DISPLAY INVISIBLE (-2650 3150);
FORCEPROP 2 LAST CDS_LOCATION U9E1
J 1
(-2175 3075);
DISPLAY 0.617021 (-2175 3075);
PAINT AQUA (-2175 3075);
DISPLAY INVISIBLE (-2175 3075);
FORCEPROP 2 LAST ROOM NIC_SPRV
J 0
(-2300 4100);
DISPLAY 1.021277 (-2300 4100);
PAINT ORANGE (-2300 4100);
DISPLAY INVISIBLE (-2300 4100);
FORCEPROP 2 LAST SEC 1
J 0
(-2300 4100);
DISPLAY 0.680851 (-2300 4100);
PAINT MONO (-2300 4100);
DISPLAY INVISIBLE (-2300 4100);
FORCEPROP 2 LAST SEC_TYPE SM
J 0
(-2300 4100);
DISPLAY 1.021277 (-2300 4100);
PAINT ORANGE (-2300 4100);
DISPLAY INVISIBLE (-2300 4100);
FORCEPROP 2 LAST BOM_COST NT_GBE_BASE
J 0
(-2300 4150);
DISPLAY 1.021277 (-2300 4150);
PAINT ORANGE (-2300 4150);
DISPLAY INVISIBLE (-2300 4150);
FORCEADD RES..2
(-3200 3300);
FORCEPROP 1 LASTPIN (-3200 3200) $PN 2
J 0
(-3195 3210);
DISPLAY 0.617021 (-3195 3210);
PAINT ORANGE (-3195 3210);
FORCEPROP 1 LAST TOLERANCE 1%
J 0
(-3155 3325);
DISPLAY 0.617021 (-3155 3325);
PAINT SKYBLUE (-3155 3325);
FORCEPROP 1 LASTPIN (-3200 3400) $PN 1
J 0
(-3195 3362);
DISPLAY 0.617021 (-3195 3362);
PAINT ORANGE (-3195 3362);
FORCEPROP 1 LAST WATTAGE 1/16W
J 0
(-3160 3275);
DISPLAY 0.617021 (-3160 3275);
PAINT SKYBLUE (-3160 3275);
FORCEPROP 1 LAST MATERIAL CHIP
J 0
(-3160 3225);
DISPLAY 0.617021 (-3160 3225);
PAINT SKYBLUE (-3160 3225);
FORCEPROP 1 LAST PACK_TYPE 0402
J 0
(-3160 3125);
DISPLAY 0.617021 (-3160 3125);
PAINT SKYBLUE (-3160 3125);
FORCEPROP 1 LAST VALUE 3.32K
J 0
(-3155 3375);
DISPLAY 0.617021 (-3155 3375);
PAINT SKYBLUE (-3155 3375);
FORCEPROP 1 LAST PART_NUMBER G21796-027
J 0
(-3160 3175);
DISPLAY 0.617021 (-3160 3175);
PAINT BLUE (-3160 3175);
FORCEPROP 1 LAST LOCATION R1R9
J 0
(-3155 3425);
DISPLAY 0.617021 (-3155 3425);
PAINT AQUA (-3155 3425);
FORCEPROP 2 LAST CDS_LIB mstr_discrete
J 0
(-3200 3300);
PAINT ORANGE (-3200 3300);
DISPLAY INVISIBLE (-3200 3300);
FORCEPROP 1 LAST PATH I10
J 0
(-3150 3475);
DISPLAY 0.978723 (-3150 3475);
PAINT WHITE (-3150 3475);
DISPLAY INVISIBLE (-3150 3475);
FORCEPROP 2 LAST ROOM NIC_SPRV
J 0
(-3150 3475);
DISPLAY 1.021277 (-3150 3475);
PAINT ORANGE (-3150 3475);
DISPLAY INVISIBLE (-3150 3475);
FORCEPROP 2 LAST SEC 1
J 0
(-3150 3525);
PAINT MONO (-3150 3525);
DISPLAY INVISIBLE (-3150 3525);
FORCEPROP 2 LAST CDS_LOCATION R1R9
J 0
(-3155 3425);
DISPLAY 0.617021 (-3155 3425);
PAINT AQUA (-3155 3425);
DISPLAY INVISIBLE (-3155 3425);
FORCEPROP 2 LAST BOM_COST NT_GBE_BASE
J 0
(-3150 3525);
DISPLAY 1.021277 (-3150 3525);
PAINT ORANGE (-3150 3525);
DISPLAY INVISIBLE (-3150 3525);
FORCEPROP 2 LAST SEC_TYPE 0402
J 0
(-3150 3525);
DISPLAY 1.021277 (-3150 3525);
PAINT ORANGE (-3150 3525);
DISPLAY INVISIBLE (-3150 3525);
FORCEADD RES..2
(-3550 3300);
FORCEPROP 1 LAST PACK_TYPE 0402
J 0
(-3510 3125);
DISPLAY 0.617021 (-3510 3125);
PAINT SKYBLUE (-3510 3125);
FORCEPROP 1 LAST MATERIAL CHIP
J 0
(-3510 3225);
DISPLAY 0.617021 (-3510 3225);
PAINT SKYBLUE (-3510 3225);
FORCEPROP 1 LAST WATTAGE 1/16W
J 0
(-3510 3275);
DISPLAY 0.617021 (-3510 3275);
PAINT SKYBLUE (-3510 3275);
FORCEPROP 1 LASTPIN (-3550 3200) $PN 2
J 0
(-3545 3210);
DISPLAY 0.617021 (-3545 3210);
PAINT ORANGE (-3545 3210);
FORCEPROP 1 LAST TOLERANCE 1%
J 0
(-3505 3325);
DISPLAY 0.617021 (-3505 3325);
PAINT SKYBLUE (-3505 3325);
FORCEPROP 1 LASTPIN (-3550 3400) $PN 1
J 0
(-3545 3362);
DISPLAY 0.617021 (-3545 3362);
PAINT ORANGE (-3545 3362);
FORCEPROP 1 LAST VALUE 3.32K
J 0
(-3505 3375);
DISPLAY 0.617021 (-3505 3375);
PAINT SKYBLUE (-3505 3375);
FORCEPROP 1 LAST LOCATION R1R3
J 0
(-3505 3425);
DISPLAY 0.617021 (-3505 3425);
PAINT AQUA (-3505 3425);
FORCEPROP 1 LAST PART_NUMBER G21796-027
J 0
(-3510 3175);
DISPLAY 0.617021 (-3510 3175);
PAINT BLUE (-3510 3175);
FORCEPROP 2 LAST CDS_LIB mstr_discrete
J 0
(-3550 3300);
PAINT ORANGE (-3550 3300);
DISPLAY INVISIBLE (-3550 3300);
FORCEPROP 2 LAST CDS_LOCATION R1R3
J 0
(-3505 3425);
DISPLAY 0.617021 (-3505 3425);
PAINT AQUA (-3505 3425);
DISPLAY INVISIBLE (-3505 3425);
FORCEPROP 1 LAST PATH I11
J 0
(-3500 3475);
DISPLAY 0.978723 (-3500 3475);
PAINT WHITE (-3500 3475);
DISPLAY INVISIBLE (-3500 3475);
FORCEPROP 2 LAST ROOM NIC_SPRV
J 0
(-3500 3475);
DISPLAY 1.021277 (-3500 3475);
PAINT ORANGE (-3500 3475);
DISPLAY INVISIBLE (-3500 3475);
FORCEPROP 2 LAST SEC_TYPE 0402
J 0
(-3500 3525);
DISPLAY 1.021277 (-3500 3525);
PAINT ORANGE (-3500 3525);
DISPLAY INVISIBLE (-3500 3525);
FORCEPROP 2 LAST BOM_COST NT_GBE_BASE
J 0
(-3500 3525);
DISPLAY 1.021277 (-3500 3525);
PAINT ORANGE (-3500 3525);
DISPLAY INVISIBLE (-3500 3525);
FORCEPROP 2 LAST SEC 1
J 0
(-3500 3525);
PAINT MONO (-3500 3525);
DISPLAY INVISIBLE (-3500 3525);
FORCEADD RES..2
(-3950 3300);
FORCEPROP 1 LASTPIN (-3950 3200) $PN 2
J 0
(-3945 3210);
DISPLAY 0.617021 (-3945 3210);
PAINT ORANGE (-3945 3210);
FORCEPROP 1 LAST TOLERANCE 1%
J 0
(-3905 3325);
DISPLAY 0.617021 (-3905 3325);
PAINT SKYBLUE (-3905 3325);
FORCEPROP 1 LASTPIN (-3950 3400) $PN 1
J 0
(-3945 3362);
DISPLAY 0.617021 (-3945 3362);
PAINT ORANGE (-3945 3362);
FORCEPROP 1 LAST WATTAGE 1/16W
J 0
(-3910 3275);
DISPLAY 0.617021 (-3910 3275);
PAINT SKYBLUE (-3910 3275);
FORCEPROP 1 LAST MATERIAL CHIP
J 0
(-3910 3225);
DISPLAY 0.617021 (-3910 3225);
PAINT SKYBLUE (-3910 3225);
FORCEPROP 1 LAST PACK_TYPE 0402
J 0
(-3910 3125);
DISPLAY 0.617021 (-3910 3125);
PAINT SKYBLUE (-3910 3125);
FORCEPROP 1 LAST VALUE 20.0K
J 0
(-3905 3375);
DISPLAY 0.617021 (-3905 3375);
PAINT SKYBLUE (-3905 3375);
FORCEPROP 1 LAST LOCATION R1R7
J 0
(-3905 3425);
DISPLAY 0.617021 (-3905 3425);
PAINT AQUA (-3905 3425);
FORCEPROP 1 LAST PART_NUMBER G21796-040
J 0
(-3910 3175);
DISPLAY 0.617021 (-3910 3175);
PAINT BLUE (-3910 3175);
FORCEPROP 2 LAST CDS_LIB mstr_discrete
J 0
(-3950 3300);
PAINT ORANGE (-3950 3300);
DISPLAY INVISIBLE (-3950 3300);
FORCEPROP 2 LAST CDS_LOCATION R1R7
J 0
(-3905 3425);
DISPLAY 0.617021 (-3905 3425);
PAINT AQUA (-3905 3425);
DISPLAY INVISIBLE (-3905 3425);
FORCEPROP 2 LAST ROOM NIC_SPRV
J 0
(-3900 3475);
DISPLAY 1.021277 (-3900 3475);
PAINT ORANGE (-3900 3475);
DISPLAY INVISIBLE (-3900 3475);
FORCEPROP 1 LAST PATH I12
J 0
(-3900 3475);
DISPLAY 0.978723 (-3900 3475);
PAINT WHITE (-3900 3475);
DISPLAY INVISIBLE (-3900 3475);
FORCEPROP 2 LAST SEC 1
J 0
(-3900 3525);
PAINT MONO (-3900 3525);
DISPLAY INVISIBLE (-3900 3525);
FORCEPROP 2 LAST SEC_TYPE 0402
J 0
(-3900 3525);
DISPLAY 1.021277 (-3900 3525);
PAINT ORANGE (-3900 3525);
DISPLAY INVISIBLE (-3900 3525);
FORCEPROP 2 LAST BOM_COST NT_GBE_BASE
J 0
(-3900 3525);
DISPLAY 1.021277 (-3900 3525);
PAINT ORANGE (-3900 3525);
DISPLAY INVISIBLE (-3900 3525);
FORCEADD P3V3_STBY..1
(-3950 3625);
FORCEPROP 3 LASTPIN (-3950 3575) SIG_NAME P3V3_STBY\g
J 0
(-3940 3585);
DISPLAY 0.659574 (-3940 3585);
PAINT MONO (-3940 3585);
DISPLAY INVISIBLE (-3940 3585);
FORCEPROP 1 LAST HDL_POWER P3V3_STBY
J 0
(-4250 3500);
DISPLAY 0.872340 (-4250 3500);
PAINT ORANGE (-4250 3500);
DISPLAY INVISIBLE (-4250 3500);
FORCEPROP 1 LAST BODY_TYPE PLUMBING
J 0
(-3995 3582);
DISPLAY 0.340426 (-3995 3582);
PAINT GREEN (-3995 3582);
DISPLAY INVISIBLE (-3995 3582);
FORCEPROP 1 LAST VOLTAGE 3.3V
J 0
(-3995 3582);
DISPLAY 0.340426 (-3995 3582);
PAINT SKYBLUE (-3995 3582);
DISPLAY INVISIBLE (-3995 3582);
FORCEPROP 1 LAST PATH I13
J 0
(-3905 3627);
DISPLAY 0.340426 (-3905 3627);
PAINT GREEN (-3905 3627);
DISPLAY INVISIBLE (-3905 3627);
FORCEPROP 1 LAST SIZE 1B
J 0
(-3905 3647);
DISPLAY 0.340426 (-3905 3647);
PAINT GREEN (-3905 3647);
DISPLAY INVISIBLE (-3905 3647);
FORCEPROP 2 LAST CDS_LIB mstr_symbols
J 0
(-3950 3625);
PAINT ORANGE (-3950 3625);
DISPLAY INVISIBLE (-3950 3625);
FORCEADD RES..2
(-3825 2350);
FORCEPROP 1 LASTPIN (-3825 2250) $PN 2
J 0
(-3820 2260);
DISPLAY 0.617021 (-3820 2260);
PAINT ORANGE (-3820 2260);
FORCEPROP 1 LAST PACK_TYPE 0402
J 0
(-3785 2175);
DISPLAY 0.617021 (-3785 2175);
PAINT SKYBLUE (-3785 2175);
FORCEPROP 1 LAST MATERIAL EMPTY
J 0
(-3785 2275);
DISPLAY 0.617021 (-3785 2275);
PAINT RED (-3785 2275);
FORCEPROP 1 LAST TOLERANCE 1%
J 0
(-3780 2375);
DISPLAY 0.617021 (-3780 2375);
PAINT SKYBLUE (-3780 2375);
FORCEPROP 1 LASTPIN (-3825 2450) $PN 1
J 0
(-3820 2412);
DISPLAY 0.617021 (-3820 2412);
PAINT ORANGE (-3820 2412);
FORCEPROP 1 LAST WATTAGE 1/16W
J 0
(-3785 2325);
DISPLAY 0.617021 (-3785 2325);
PAINT SKYBLUE (-3785 2325);
FORCEPROP 1 LAST VALUE 3.32K
J 0
(-3780 2425);
DISPLAY 0.617021 (-3780 2425);
PAINT SKYBLUE (-3780 2425);
FORCEPROP 1 LAST LOCATION R1R6
J 0
(-3780 2475);
DISPLAY 0.617021 (-3780 2475);
PAINT AQUA (-3780 2475);
FORCEPROP 1 LAST PART_NUMBER G21796-027
J 0
(-3785 2225);
DISPLAY 0.617021 (-3785 2225);
PAINT BLUE (-3785 2225);
FORCEPROP 2 LAST CDS_LIB mstr_discrete
J 0
(-3825 2350);
PAINT ORANGE (-3825 2350);
DISPLAY INVISIBLE (-3825 2350);
FORCEPROP 2 LAST CDS_LOCATION R1R6
J 0
(-3780 2475);
DISPLAY 0.617021 (-3780 2475);
PAINT AQUA (-3780 2475);
DISPLAY INVISIBLE (-3780 2475);
FORCEPROP 2 LAST ROOM NIC_SPRV
J 0
(-3775 2525);
DISPLAY 1.021277 (-3775 2525);
PAINT ORANGE (-3775 2525);
DISPLAY INVISIBLE (-3775 2525);
FORCEPROP 1 LAST PATH I14
J 0
(-3775 2525);
DISPLAY 0.978723 (-3775 2525);
PAINT WHITE (-3775 2525);
DISPLAY INVISIBLE (-3775 2525);
FORCEPROP 2 LAST BOM_COST NT_GBE_BASE
J 0
(-3775 2575);
DISPLAY 1.021277 (-3775 2575);
PAINT ORANGE (-3775 2575);
DISPLAY INVISIBLE (-3775 2575);
FORCEPROP 2 LAST SEC_TYPE 0402
J 0
(-3775 2575);
DISPLAY 1.021277 (-3775 2575);
PAINT ORANGE (-3775 2575);
DISPLAY INVISIBLE (-3775 2575);
FORCEPROP 2 LAST SEC 1
J 0
(-3775 2575);
PAINT MONO (-3775 2575);
DISPLAY INVISIBLE (-3775 2575);
FORCEADD GND..1
(-3825 2075);
FORCEPROP 3 LASTPIN (-3825 2125) SIG_NAME GND\g
J 0
(-3815 2135);
DISPLAY 0.659574 (-3815 2135);
PAINT MONO (-3815 2135);
DISPLAY INVISIBLE (-3815 2135);
FORCEPROP 1 LAST BODY_TYPE PLUMBING
J 0
(-3870 2032);
DISPLAY 0.340426 (-3870 2032);
PAINT GREEN (-3870 2032);
DISPLAY INVISIBLE (-3870 2032);
FORCEPROP 1 LAST VOLTAGE 0.0V
J 0
(-3870 2032);
DISPLAY 0.340426 (-3870 2032);
PAINT SKYBLUE (-3870 2032);
DISPLAY INVISIBLE (-3870 2032);
FORCEPROP 1 LAST SIZE 1B
J 0
(-3750 2025);
DISPLAY 0.872340 (-3750 2025);
PAINT AQUA (-3750 2025);
DISPLAY INVISIBLE (-3750 2025);
FORCEPROP 1 LAST PATH I16
J 0
(-3750 2075);
DISPLAY 0.872340 (-3750 2075);
PAINT AQUA (-3750 2075);
DISPLAY INVISIBLE (-3750 2075);
FORCEPROP 2 LAST CDS_LIB mstr_symbols
J 0
(-3825 2075);
PAINT ORANGE (-3825 2075);
DISPLAY INVISIBLE (-3825 2075);
FORCEPROP 1 LAST HDL_POWER GND
J 0
(-3825 2225);
DISPLAY 0.872340 (-3825 2225);
PAINT GREEN (-3825 2225);
DISPLAY INVISIBLE (-3825 2225);
FORCEADD RES..1
(-1400 2750);
FORCEPROP 1 LAST WATTAGE 1/16W
J 2
(-1550 2725);
DISPLAY 0.617021 (-1550 2725);
PAINT SKYBLUE (-1550 2725);
FORCEPROP 1 LAST VALUE 33.2
J 2
(-1450 2725);
DISPLAY 0.617021 (-1450 2725);
PAINT SKYBLUE (-1450 2725);
FORCEPROP 1 LASTPIN (-1500 2750) $PN 1
J 0
(-1488 2762);
DISPLAY 0.617021 (-1488 2762);
PAINT ORANGE (-1488 2762);
FORCEPROP 1 LAST TOLERANCE 1%
J 0
(-1350 2725);
DISPLAY 0.617021 (-1350 2725);
PAINT SKYBLUE (-1350 2725);
FORCEPROP 1 LASTPIN (-1300 2750) $PN 2
J 0
(-1338 2762);
DISPLAY 0.617021 (-1338 2762);
PAINT ORANGE (-1338 2762);
FORCEPROP 1 LAST LOCATION R9E6
J 0
(-1450 2800);
DISPLAY 0.617021 (-1450 2800);
PAINT AQUA (-1450 2800);
FORCEPROP 1 LAST PART_NUMBER G21796-074
J 0
(-1275 2700);
DISPLAY 0.617021 (-1275 2700);
PAINT BLUE (-1275 2700);
FORCEPROP 1 LAST MATERIAL CHIP
J 0
(-1650 2725);
DISPLAY 0.617021 (-1650 2725);
PAINT SKYBLUE (-1650 2725);
DISPLAY INVISIBLE (-1650 2725);
FORCEPROP 2 LAST CDS_LIB mstr_discrete
J 0
(-1400 2750);
PAINT ORANGE (-1400 2750);
DISPLAY INVISIBLE (-1400 2750);
FORCEPROP 2 LAST CDS_LOCATION R9E6
J 0
(-1450 2800);
DISPLAY 0.617021 (-1450 2800);
PAINT AQUA (-1450 2800);
DISPLAY INVISIBLE (-1450 2800);
FORCEPROP 2 LAST SEC_TYPE 0402
J 0
(-1450 2950);
DISPLAY 1.021277 (-1450 2950);
PAINT ORANGE (-1450 2950);
DISPLAY INVISIBLE (-1450 2950);
FORCEPROP 2 LAST BOM_COST NT_GBE_BASE
J 0
(-1450 2900);
DISPLAY 1.021277 (-1450 2900);
PAINT ORANGE (-1450 2900);
DISPLAY INVISIBLE (-1450 2900);
FORCEPROP 2 LAST SEC 1
J 0
(-1450 2950);
PAINT MONO (-1450 2950);
DISPLAY INVISIBLE (-1450 2950);
FORCEPROP 1 LAST PATH I17
J 0
(-1450 2900);
DISPLAY 0.978723 (-1450 2900);
PAINT WHITE (-1450 2900);
DISPLAY INVISIBLE (-1450 2900);
FORCEPROP 2 LAST ROOM NIC_SPRV
J 0
(-1450 2850);
DISPLAY 1.021277 (-1450 2850);
PAINT ORANGE (-1450 2850);
DISPLAY INVISIBLE (-1450 2850);
FORCEPROP 1 LAST PACK_TYPE 0402
J 0
(-1275 2725);
DISPLAY 0.617021 (-1275 2725);
PAINT SKYBLUE (-1275 2725);
DISPLAY INVISIBLE (-1275 2725);
FORCEADD CAP_A..1
(-2475 3375);
FORCEPROP 1 LASTPIN (-2475 3275) $PN 2
J 0
(-2465 3255);
DISPLAY 0.617021 (-2465 3255);
PAINT ORANGE (-2465 3255);
FORCEPROP 1 LAST MATERIAL X7R
J 0
(-2425 3275);
DISPLAY 0.617021 (-2425 3275);
PAINT SKYBLUE (-2425 3275);
FORCEPROP 1 LAST TOLERANCE 10%
J 0
(-2425 3325);
DISPLAY 0.617021 (-2425 3325);
PAINT SKYBLUE (-2425 3325);
FORCEPROP 1 LASTPIN (-2475 3475) $PN 1
J 0
(-2465 3455);
DISPLAY 0.617021 (-2465 3455);
PAINT ORANGE (-2465 3455);
FORCEPROP 1 LAST VOLTAGE 16V
J 0
(-2425 3375);
DISPLAY 0.617021 (-2425 3375);
PAINT SKYBLUE (-2425 3375);
FORCEPROP 1 LAST PACK_TYPE 0402V
J 0
(-2425 3175);
DISPLAY 0.617021 (-2425 3175);
PAINT SKYBLUE (-2425 3175);
FORCEPROP 1 LAST VALUE 0.1UF
J 0
(-2425 3425);
DISPLAY 0.617021 (-2425 3425);
PAINT SKYBLUE (-2425 3425);
FORCEPROP 1 LAST PART_NUMBER A36096-030
J 0
(-2425 3225);
DISPLAY 0.617021 (-2425 3225);
PAINT BLUE (-2425 3225);
FORCEPROP 1 LAST LOCATION C1R25
J 0
(-2425 3475);
DISPLAY 0.617021 (-2425 3475);
PAINT AQUA (-2425 3475);
FORCEPROP 2 LAST CDS_LIB dev_discrete
J 0
(-2475 3375);
PAINT ORANGE (-2475 3375);
DISPLAY INVISIBLE (-2475 3375);
FORCEPROP 1 LAST PATH I3
J 0
(-2425 3525);
DISPLAY 0.978723 (-2425 3525);
PAINT WHITE (-2425 3525);
DISPLAY INVISIBLE (-2425 3525);
FORCEPROP 2 LAST ROOM NIC_SPRV
J 0
(-2425 3525);
DISPLAY 1.021277 (-2425 3525);
PAINT ORANGE (-2425 3525);
DISPLAY INVISIBLE (-2425 3525);
FORCEPROP 2 LAST CDS_LOCATION C1R25
J 0
(-2425 3475);
DISPLAY 0.617021 (-2425 3475);
PAINT AQUA (-2425 3475);
DISPLAY INVISIBLE (-2425 3475);
FORCEPROP 2 LAST CDS_SEC 1
J 0
(-2425 3525);
PAINT ORANGE (-2425 3525);
DISPLAY INVISIBLE (-2425 3525);
FORCEPROP 2 LAST SEC 1
J 0
(-2425 3575);
PAINT MONO (-2425 3575);
DISPLAY INVISIBLE (-2425 3575);
FORCEPROP 2 LAST SEC_TYPE 0402V
J 0
(-2425 3575);
DISPLAY 1.021277 (-2425 3575);
PAINT ORANGE (-2425 3575);
DISPLAY INVISIBLE (-2425 3575);
FORCEPROP 2 LAST BOM_COST NT_GBE_BASE
J 0
(-2425 3575);
DISPLAY 1.021277 (-2425 3575);
PAINT ORANGE (-2425 3575);
DISPLAY INVISIBLE (-2425 3575);
FORCEADD GND..1
(-2475 3100);
FORCEPROP 3 LASTPIN (-2475 3150) SIG_NAME GND\g
J 0
(-2465 3160);
DISPLAY 0.659574 (-2465 3160);
PAINT MONO (-2465 3160);
DISPLAY INVISIBLE (-2465 3160);
FORCEPROP 1 LAST BODY_TYPE PLUMBING
J 0
(-2520 3057);
DISPLAY 0.340426 (-2520 3057);
PAINT GREEN (-2520 3057);
DISPLAY INVISIBLE (-2520 3057);
FORCEPROP 1 LAST VOLTAGE 0.0V
J 0
(-2520 3057);
DISPLAY 0.340426 (-2520 3057);
PAINT SKYBLUE (-2520 3057);
DISPLAY INVISIBLE (-2520 3057);
FORCEPROP 1 LAST SIZE 1B
J 0
(-2400 3050);
DISPLAY 0.872340 (-2400 3050);
PAINT AQUA (-2400 3050);
DISPLAY INVISIBLE (-2400 3050);
FORCEPROP 2 LAST CDS_LIB mstr_symbols
J 0
(-2475 3100);
PAINT ORANGE (-2475 3100);
DISPLAY INVISIBLE (-2475 3100);
FORCEPROP 1 LAST HDL_POWER GND
J 0
(-2475 3250);
DISPLAY 0.872340 (-2475 3250);
PAINT GREEN (-2475 3250);
DISPLAY INVISIBLE (-2475 3250);
FORCEPROP 1 LAST PATH I4
J 0
(-2400 3100);
DISPLAY 0.872340 (-2400 3100);
PAINT AQUA (-2400 3100);
DISPLAY INVISIBLE (-2400 3100);
FORCEADD OFFPAGE..1
(-4475 2750);
FORCEPROP 2 LAST $XR0 139 
J 0
(-4727 2750);
DISPLAY 0.638298 (-4727 2750);
PAINT MONO (-4727 2750);
FORCEPROP 2 LAST CDS_LIB mstr_standard
J 0
(-4475 2750);
PAINT ORANGE (-4475 2750);
DISPLAY INVISIBLE (-4475 2750);
FORCEPROP 2 LAST PATH I5
J 0
(-4425 2825);
DISPLAY 1.021277 (-4425 2825);
PAINT ORANGE (-4425 2825);
DISPLAY INVISIBLE (-4425 2825);
FORCEPROP 1 LAST COMMENT_BODY TRUE
J 0
(-4350 2650);
DISPLAY 0.872340 (-4350 2650);
PAINT GREEN (-4350 2650);
DISPLAY INVISIBLE (-4350 2650);
FORCEPROP 1 LAST OFFPAGE TRUE
J 0
(-4150 2625);
DISPLAY 0.872340 (-4150 2625);
PAINT GREEN (-4150 2625);
DISPLAY INVISIBLE (-4150 2625);
FORCEADD OFFPAGE..1
(-4475 2650);
FORCEPROP 2 LAST $XR0 139 
J 0
(-4727 2650);
DISPLAY 0.638298 (-4727 2650);
PAINT MONO (-4727 2650);
FORCEPROP 1 LAST COMMENT_BODY TRUE
J 0
(-4350 2550);
DISPLAY 0.872340 (-4350 2550);
PAINT GREEN (-4350 2550);
DISPLAY INVISIBLE (-4350 2550);
FORCEPROP 1 LAST OFFPAGE TRUE
J 0
(-4150 2525);
DISPLAY 0.872340 (-4150 2525);
PAINT GREEN (-4150 2525);
DISPLAY INVISIBLE (-4150 2525);
FORCEPROP 2 LAST PATH I6
J 0
(-4425 2725);
DISPLAY 1.021277 (-4425 2725);
PAINT ORANGE (-4425 2725);
DISPLAY INVISIBLE (-4425 2725);
FORCEPROP 2 LAST CDS_LIB mstr_standard
J 0
(-4475 2650);
PAINT ORANGE (-4475 2650);
DISPLAY INVISIBLE (-4475 2650);
FORCEADD OFFPAGE..1
(-4475 2550);
FORCEPROP 2 LAST $XR0 139 
J 0
(-4901 2550);
DISPLAY 0.638298 (-4901 2550);
PAINT MONO (-4901 2550);
DISPLAY INVISIBLE (-4901 2550);
FORCEPROP 1 LAST COMMENT_BODY TRUE
J 0
(-4350 2450);
DISPLAY 0.872340 (-4350 2450);
PAINT GREEN (-4350 2450);
DISPLAY INVISIBLE (-4350 2450);
FORCEPROP 1 LAST OFFPAGE TRUE
J 0
(-4150 2425);
DISPLAY 0.872340 (-4150 2425);
PAINT GREEN (-4150 2425);
DISPLAY INVISIBLE (-4150 2425);
FORCEPROP 2 LAST CDS_LIB mstr_standard
J 0
(-4475 2550);
PAINT ORANGE (-4475 2550);
DISPLAY INVISIBLE (-4475 2550);
FORCEPROP 2 LAST PATH I7
J 0
(-4425 2625);
DISPLAY 1.021277 (-4425 2625);
PAINT ORANGE (-4425 2625);
DISPLAY INVISIBLE (-4425 2625);
FORCEADD OFFPAGE..2
(-825 2750);
FORCEPROP 2 LAST $XR0 139 
J 0
(-636 2750);
DISPLAY 0.638298 (-636 2750);
PAINT MONO (-636 2750);
FORCEPROP 2 LAST PATH I8
J 0
(-775 2825);
DISPLAY 1.021277 (-775 2825);
PAINT ORANGE (-775 2825);
DISPLAY INVISIBLE (-775 2825);
FORCEPROP 1 LAST COMMENT_BODY TRUE
J 0
(-870 2655);
DISPLAY 0.872340 (-870 2655);
PAINT GREEN (-870 2655);
DISPLAY INVISIBLE (-870 2655);
FORCEPROP 2 LAST CDS_LIB mstr_standard
J 0
(-825 2750);
PAINT ORANGE (-825 2750);
DISPLAY INVISIBLE (-825 2750);
FORCEPROP 1 LAST OFFPAGE TRUE
J 0
(-500 2625);
DISPLAY 0.872340 (-500 2625);
PAINT GREEN (-500 2625);
DISPLAY INVISIBLE (-500 2625);
FORCEADD GND..1
(-1900 2175);
FORCEPROP 3 LASTPIN (-1900 2225) SIG_NAME GND\g
J 0
(-1890 2235);
DISPLAY 0.659574 (-1890 2235);
PAINT MONO (-1890 2235);
DISPLAY INVISIBLE (-1890 2235);
FORCEPROP 1 LAST VOLTAGE 0.0V
J 0
(-1945 2132);
DISPLAY 0.340426 (-1945 2132);
PAINT SKYBLUE (-1945 2132);
DISPLAY INVISIBLE (-1945 2132);
FORCEPROP 1 LAST SIZE 1B
J 0
(-1825 2125);
DISPLAY 0.872340 (-1825 2125);
PAINT AQUA (-1825 2125);
DISPLAY INVISIBLE (-1825 2125);
FORCEPROP 2 LAST CDS_LIB mstr_symbols
J 0
(-1900 2175);
PAINT ORANGE (-1900 2175);
DISPLAY INVISIBLE (-1900 2175);
FORCEPROP 1 LAST BODY_TYPE PLUMBING
J 0
(-1945 2132);
DISPLAY 0.340426 (-1945 2132);
PAINT GREEN (-1945 2132);
DISPLAY INVISIBLE (-1945 2132);
FORCEPROP 1 LAST PATH I9
J 0
(-1825 2175);
DISPLAY 0.872340 (-1825 2175);
PAINT AQUA (-1825 2175);
DISPLAY INVISIBLE (-1825 2175);
FORCEPROP 1 LAST HDL_POWER GND
J 0
(-1900 2325);
DISPLAY 0.872340 (-1900 2325);
PAINT GREEN (-1900 2325);
DISPLAY INVISIBLE (-1900 2325);
FORCEADD DNS..2
(-3820 2345);
PAINT RED (-3820 2345);
FORCEPROP 1 LAST COMMENT_BODY TRUE
R 1
J 0
(-3745 2120);
DISPLAY 0.872340 (-3745 2120);
PAINT GREEN (-3745 2120);
DISPLAY INVISIBLE (-3745 2120);
FORCEPROP 2 LAST CDS_LIB mstr_misc
J 0
(-3820 2345);
PAINT ORANGE (-3820 2345);
DISPLAY INVISIBLE (-3820 2345);
FORCEADD INTEL_CORP_BPAGE..1
(-50 0);
FORCEPROP 1 LAST CDS_CON_LAST_MODIFIED Tue Dec 01 11:52:03 2015
J 0
(-1475 325);
DISPLAY 0.659574 (-1475 325);
PAINT GREEN (-1475 325);
DISPLAY INVISIBLE (-1475 325);
FORCEPROP 1 LAST CUSTOM_TXT_CDS <CURRENT_DESIGN_SHEET> OF <TOTAL_DESIGN_SHEETS>
J 0
(-550 25);
PAINT GREEN (-550 25);
FORCEPROP 2 LAST CUSTOM_TXT_CDS <XR_PAGE_TITLE>
J 0
(-7940 5250);
DISPLAY 0.638298 (-7940 5250);
PAINT PINK (-7940 5250);
DISPLAY INVISIBLE (-7940 5250);
FORCEPROP 2 LAST CUSTOM_TXT_CDS <CON_LAST_MODIFIED>
J 0
(-1975 350);
DISPLAY 0.765957 (-1975 350);
PAINT ORANGE (-1975 350);
FORCEPROP 1 LAST SCH_TITLE LAN SPRINGVILLE I210 (2/3)
J 0
(-8000 50);
DISPLAY 1.212766 (-8000 50);
PAINT GREEN (-8000 50);
FORCEPROP 1 LAST SCH_ADDRESS1 2200 Mission College Blvd.
J 0
(-4025 125);
DISPLAY 0.617021 (-4025 125);
PAINT GREEN (-4025 125);
FORCEPROP 1 LAST SCH_ADDRESS2 P.O. BOX 58119
J 0
(-4025 75);
DISPLAY 0.617021 (-4025 75);
PAINT GREEN (-4025 75);
FORCEPROP 1 LAST SCH_ADDRESS3 Santa Clara, CA 95052-8119
J 0
(-4025 25);
DISPLAY 0.617021 (-4025 25);
PAINT GREEN (-4025 25);
FORCEPROP 1 LAST SCH_NUMBER H4694802
J 0
(-1350 150);
DISPLAY 1.212766 (-1350 150);
PAINT YELLOW (-1350 150);
FORCEPROP 1 LAST SCH_DEPT BESD
J 1
(-4500 100);
DISPLAY 1.212766 (-4500 100);
PAINT YELLOW (-4500 100);
FORCEPROP 1 LAST SCH_REV 2.420
J 0
(-300 150);
DISPLAY 0.978723 (-300 150);
PAINT YELLOW (-300 150);
FORCEPROP 2 LAST CDS_LIB mstr_symbols
J 0
(-50 0);
DISPLAY 0.489362 (-50 0);
PAINT ORANGE (-50 0);
DISPLAY INVISIBLE (-50 0);
FORCEPROP 2 LAST PAGE_BORDER TRUE
J 0
(-7940 5250);
DISPLAY 0.638298 (-7940 5250);
PAINT PINK (-7940 5250);
DISPLAY INVISIBLE (-7940 5250);
FORCEPROP 1 LAST COMMENT_BODY TRUE
J 0
(-38 12);
DISPLAY 0.319149 (-38 12);
PAINT GREEN (-38 12);
DISPLAY INVISIBLE (-38 12);
FORCEPROP 2 LAST CDS_XR_PAGE_TITLE CR-140 : @BASEBOARD_FAB2_LIB.BASEBOARD_FAB2(SCH_1):PAGE140
J 0
(-7940 5250);
DISPLAY 0.638298 (-7940 5250);
PAINT PINK (-7940 5250);
DISPLAY INVISIBLE (-7940 5250);
WIRE 16 -1 (-2475 3475)(-2475 3525);
WIRE 16 -1 (-2475 3525)(-2825 3525);
WIRE 16 -1 (-2825 3525)(-2825 2850);
WIRE 16 -1 (-3200 3525)(-2825 3525);
WIRE 16 -1 (-3200 3400)(-3200 3525);
WIRE 16 -1 (-3550 3525)(-3200 3525);
WIRE 16 -1 (-2825 2850)(-2700 2850);
WIRE 16 -1 (-3550 3400)(-3550 3525);
WIRE 16 -1 (-3950 3525)(-3550 3525);
WIRE 16 -1 (-3950 3400)(-3950 3525);
WIRE 16 -1 (-3950 3575)(-3950 3525);
WIRE 16 -1 (-3825 2125)(-3825 2250);
WIRE 16 -1 (-2475 3150)(-2475 3275);
WIRE 16 -1 (-1900 2500)(-2000 2500);
WIRE 16 -1 (-1900 2225)(-1900 2500);
WIRE 16 -1 (-1300 2750)(-875 2750);
FORCEPROP 2 LAST SIG_NAME SPI_NIC_MISO
J 0
(-1160 2760);
DISPLAY 0.617021 (-1160 2760);
PAINT ORANGE (-1160 2760);
WIRE 16 -1 (-2000 2750)(-1500 2750);
FORCEPROP 2 LAST SIG_NAME SPI_NIC_MISO_R
J 0
(-1885 2760);
DISPLAY 0.617021 (-1885 2760);
PAINT ORANGE (-1885 2760);
FORCEPROP 2 LASTPROP $XRERR UNIQUE?
J 0
(-2125 2760);
DISPLAY 0.638298 (-2125 2760);
PAINT MONO (-2125 2760);
DISPLAY INVISIBLE (-2125 2760);
WIRE 16 -1 (-2700 2750)(-3825 2750);
WIRE 16 -1 (-3825 2750)(-3950 2750);
WIRE 16 -1 (-3825 2450)(-3825 2750);
WIRE 16 -1 (-3950 3200)(-3950 2750);
WIRE 16 -1 (-3950 2750)(-4425 2750);
FORCEPROP 2 LAST SIG_NAME SPI_NIC_MOSI
J 0
(-4425 2760);
DISPLAY 0.617021 (-4425 2760);
PAINT ORANGE (-4425 2760);
WIRE 16 -1 (-3200 2600)(-2700 2600);
FORCEPROP 2 LAST SIG_NAME PU_NV_HOLD_N
J 0
(-3060 2610);
DISPLAY 0.617021 (-3060 2610);
PAINT ORANGE (-3060 2610);
FORCEPROP 2 LASTPROP $XRERR UNIQUE?
J 0
(-3300 2610);
DISPLAY 0.638298 (-3300 2610);
PAINT MONO (-3300 2610);
DISPLAY INVISIBLE (-3300 2610);
WIRE 16 -1 (-3200 3200)(-3200 2600);
WIRE 16 -1 (-3550 2500)(-2700 2500);
FORCEPROP 2 LAST SIG_NAME PU_NV_WP_N
J 0
(-3035 2510);
DISPLAY 0.617021 (-3035 2510);
PAINT ORANGE (-3035 2510);
FORCEPROP 2 LASTPROP $XRERR UNIQUE?
J 0
(-3275 2510);
DISPLAY 0.638298 (-3275 2510);
PAINT MONO (-3275 2510);
DISPLAY INVISIBLE (-3275 2510);
WIRE 16 -1 (-3550 3200)(-3550 2500);
WIRE 16 -1 (-2700 2650)(-4425 2650);
FORCEPROP 2 LAST SIG_NAME SPI_NIC_SCLK
J 0
(-4425 2660);
DISPLAY 0.617021 (-4425 2660);
PAINT ORANGE (-4425 2660);
WIRE 16 -1 (-2700 2550)(-4425 2550);
FORCEPROP 2 LAST SIG_NAME SPI_NIC_CS_N
J 0
(-4425 2560);
DISPLAY 0.617021 (-4425 2560);
PAINT ORANGE (-4425 2560);
DOT 1 (-2825 3525);
DOT 1 (-3200 3525);
DOT 1 (-3550 3525);
DOT 1 (-3950 3525);
DOT 1 (-3825 2750);
DOT 1 (-3950 2750);
FORCENOTE
$CDS_IMAGE|Crescent_City_RMII_Block_0.JPG|2082|4000
(-6725 2500) 0;
DISPLAY CENTER (-6725 2500);
PAINT MONO (-6725 2500);
QUIT
